(kicad_pcb
	(version 20241229)
	(generator "pcbnew")
	(generator_version "9.0")
	(general
		(thickness 1.63)
		(legacy_teardrops no)
	)
	(paper "A4")
	(title_block
		(title "CM4 Baseboard")
		(date "2026-01-05")
		(rev "1.1.1")
		(company "Antmicro Ltd")
		(comment 1 "www.antmicro.com")
		(comment 9 "footprints 462-464 of 506")
	)
	(layers
		(0 "F.Cu" signal)
		(4 "In1.Cu" power)
		(6 "In2.Cu" power)
		(8 "In3.Cu" signal)
		(10 "In4.Cu" signal)
		(2 "B.Cu" signal)
		(9 "F.Adhes" user "F.Adhesive")
		(11 "B.Adhes" user "B.Adhesive")
		(13 "F.Paste" user)
		(15 "B.Paste" user)
		(5 "F.SilkS" user "F.Silkscreen")
		(7 "B.SilkS" user "B.Silkscreen")
		(1 "F.Mask" user)
		(3 "B.Mask" user)
		(17 "Dwgs.User" user "User.Drawings")
		(19 "Cmts.User" user "User.Comments")
		(21 "Eco1.User" user "User.Eco1")
		(23 "Eco2.User" user "User.Eco2")
		(25 "Edge.Cuts" user)
		(27 "Margin" user)
		(31 "F.CrtYd" user "F.Courtyard")
		(29 "B.CrtYd" user "B.Courtyard")
		(35 "F.Fab" user)
		(33 "B.Fab" user)
	)
	(footprint "antmicro-footprints:Conn_Socket_Molex_SlimStack_2x20_543630489"
		(layer "B.Cu")
		(at 94.067962 171.9395 90)
		(property "Reference" "J701"
			(at 6.923 4.37 270)
			(layer "B.SilkS")
			(effects
				(font
					(size 0.7 0.7)
					(thickness 0.15)
				)
				(justify left bottom mirror)
			)
		)
		(property "Value" "Socket_Molex_SlimStack_2x20_543630489"
			(at 0 -4.65 270)
			(layer "B.Fab")
			(effects
				(font
					(size 0.7 0.7)
					(thickness 0.15)
				)
				(justify left bottom mirror)
			)
		)
		(property "Datasheet" "https://www.molex.com/pdm_docs/sd/543630489_sd.pdf"
			(at 0 0 90)
			(layer "B.Fab")
			(hide yes)
			(effects
				(font
					(size 1.27 1.27)
					(thickness 0.15)
				)
			)
		)
		(property "MPN" "543630489"
			(at 0 0 90)
			(unlocked yes)
			(layer "B.Fab")
			(hide yes)
			(effects
				(font
					(size 1 1)
					(thickness 0.15)
				)
				(justify mirror)
			)
		)
		(property "Manufacturer" "Molex"
			(at 0 0 90)
			(unlocked yes)
			(layer "B.Fab")
			(hide yes)
			(effects
				(font
					(size 1 1)
					(thickness 0.15)
				)
				(justify mirror)
			)
		)
		(property "Pitch" "0.5 mm"
			(at 0 0 90)
			(unlocked yes)
			(layer "B.Fab")
			(hide yes)
			(effects
				(font
					(size 1 1)
					(thickness 0.15)
				)
				(justify mirror)
			)
		)
		(property "Author" "Antmicro"
			(at 0 0 90)
			(unlocked yes)
			(layer "B.Fab")
			(hide yes)
			(effects
				(font
					(size 1 1)
					(thickness 0.15)
				)
				(justify mirror)
			)
		)
		(property "License" "Apache-2.0"
			(at 0 0 90)
			(unlocked yes)
			(layer "B.Fab")
			(hide yes)
			(effects
				(font
					(size 1 1)
					(thickness 0.15)
				)
				(justify mirror)
			)
		)
		(sheetname "/Display/")
		(sheetfile "display.kicad_sch")
		(attr smd)
		(fp_line
			(start 7 2.5)
			(end 7 -2.5)
			(stroke
				(width 0.15)
				(type solid)
			)
			(layer "B.SilkS")
		)
		(fp_line
			(start -7 2.5)
			(end -7 -2.5)
			(stroke
				(width 0.15)
				(type solid)
			)
			(layer "B.SilkS")
		)
		(fp_circle
			(center -5.1 -3.1)
			(end -5.05 -3.1)
			(stroke
				(width 0.15)
				(type solid)
			)
			(fill yes)
			(layer "B.SilkS")
		)
		(fp_rect
			(start -7.3 3.6)
			(end 7.3 -3.6)
			(stroke
				(width 0.05)
				(type solid)
			)
			(fill no)
			(layer "B.CrtYd")
		)
		(fp_text user "License: Apache-2.0"
			(at -7.7 -6.3 270)
			(layer "B.Fab")
			(effects
				(font
					(size 0.7 0.7)
					(thickness 0.15)
				)
				(justify left bottom mirror)
			)
		)
		(fp_text user "Author: Antmicro"
			(at -7.7 -8.7 270)
			(layer "B.Fab")
			(effects
				(font
					(size 0.7 0.7)
					(thickness 0.15)
				)
				(justify left bottom mirror)
			)
		)
		(fp_text user "${REFERENCE}"
			(at -7.7 -7.5 270)
			(layer "B.Fab")
			(effects
				(font
					(size 0.7 0.7)
					(thickness 0.15)
				)
				(justify left bottom mirror)
			)
		)
		(pad "1" smd rect
			(at -4.748 -2.755 270)
			(size 0.3 1.1)
			(layers "B.Cu" "B.Mask" "B.Paste")
			(net 3 "GND")
			(pintype "passive")
		)
		(pad "2" smd rect
			(at -4.748 2.742 270)
			(size 0.3 1.1)
			(layers "B.Cu" "B.Mask" "B.Paste")
			(net 3 "GND")
			(pintype "passive")
		)
		(pad "3" smd rect
			(at -4.248 -2.755 270)
			(size 0.3 1.1)
			(layers "B.Cu" "B.Mask" "B.Paste")
			(net 96 "/Compute module/DSI.D3_N")
			(pintype "passive")
		)
		(pad "4" smd rect
			(at -4.248 2.742 270)
			(size 0.3 1.1)
			(layers "B.Cu" "B.Mask" "B.Paste")
			(net 464 "Net-(D709-C)")
			(pintype "passive")
		)
		(pad "5" smd rect
			(at -3.748 -2.755 270)
			(size 0.3 1.1)
			(layers "B.Cu" "B.Mask" "B.Paste")
			(net 98 "/Compute module/DSI.D3_P")
			(pintype "passive")
		)
		(pad "6" smd rect
			(at -3.748 2.742 270)
			(size 0.3 1.1)
			(layers "B.Cu" "B.Mask" "B.Paste")
			(net 464 "Net-(D709-C)")
			(pintype "passive")
		)
		(pad "7" smd rect
			(at -3.248 -2.755 270)
			(size 0.3 1.1)
			(layers "B.Cu" "B.Mask" "B.Paste")
			(net 3 "GND")
			(pintype "passive")
		)
		(pad "8" smd rect
			(at -3.248 2.742 270)
			(size 0.3 1.1)
			(layers "B.Cu" "B.Mask" "B.Paste")
			(net 464 "Net-(D709-C)")
			(pintype "passive")
		)
		(pad "9" smd rect
			(at -2.748 -2.755 270)
			(size 0.3 1.1)
			(layers "B.Cu" "B.Mask" "B.Paste")
			(net 87 "/Compute module/DSI.D2_N")
			(pintype "passive")
		)
		(pad "10" smd rect
			(at -2.748 2.742 270)
			(size 0.3 1.1)
			(layers "B.Cu" "B.Mask" "B.Paste")
			(net 464 "Net-(D709-C)")
			(pintype "passive")
		)
		(pad "11" smd rect
			(at -2.248 -2.755 270)
			(size 0.3 1.1)
			(layers "B.Cu" "B.Mask" "B.Paste")
			(net 97 "/Compute module/DSI.D2_P")
			(pintype "passive")
		)
		(pad "12" smd rect
			(at -2.248 2.742 270)
			(size 0.3 1.1)
			(layers "B.Cu" "B.Mask" "B.Paste")
			(net 9 "+3V3")
			(pintype "passive")
		)
		(pad "13" smd rect
			(at -1.748 -2.755 270)
			(size 0.3 1.1)
			(layers "B.Cu" "B.Mask" "B.Paste")
			(net 3 "GND")
			(pintype "passive")
		)
		(pad "14" smd rect
			(at -1.748 2.742 270)
			(size 0.3 1.1)
			(layers "B.Cu" "B.Mask" "B.Paste")
			(net 3 "GND")
			(pintype "passive")
		)
		(pad "15" smd rect
			(at -1.248 -2.755 270)
			(size 0.3 1.1)
			(layers "B.Cu" "B.Mask" "B.Paste")
			(net 74 "/Compute module/DSI.D1_N")
			(pintype "passive")
		)
		(pad "16" smd rect
			(at -1.248 2.742 270)
			(size 0.3 1.1)
			(layers "B.Cu" "B.Mask" "B.Paste")
			(net 301 "Net-(R705-R1.1)")
			(pintype "passive")
		)
		(pad "17" smd rect
			(at -0.748 -2.755 270)
			(size 0.3 1.1)
			(layers "B.Cu" "B.Mask" "B.Paste")
			(net 75 "/Compute module/DSI.D1_P")
			(pintype "passive")
		)
		(pad "18" smd rect
			(at -0.748 2.742 270)
			(size 0.3 1.1)
			(layers "B.Cu" "B.Mask" "B.Paste")
			(net 302 "Net-(R705-R2.1)")
			(pintype "passive")
		)
		(pad "19" smd rect
			(at -0.248 -2.755 270)
			(size 0.3 1.1)
			(layers "B.Cu" "B.Mask" "B.Paste")
			(net 3 "GND")
			(pintype "passive")
		)
		(pad "20" smd rect
			(at -0.248 2.742 270)
			(size 0.3 1.1)
			(layers "B.Cu" "B.Mask" "B.Paste")
			(net 303 "Net-(R705-R3.1)")
			(pintype "passive")
		)
		(pad "21" smd rect
			(at 0.252 -2.755 270)
			(size 0.3 1.1)
			(layers "B.Cu" "B.Mask" "B.Paste")
			(net 72 "/Compute module/DSI.D0_N")
			(pintype "passive")
		)
		(pad "22" smd rect
			(at 0.252 2.742 270)
			(size 0.3 1.1)
			(layers "B.Cu" "B.Mask" "B.Paste")
			(net 304 "Net-(R705-R4.1)")
			(pintype "passive")
		)
		(pad "23" smd rect
			(at 0.752 -2.755 270)
			(size 0.3 1.1)
			(layers "B.Cu" "B.Mask" "B.Paste")
			(net 73 "/Compute module/DSI.D0_P")
			(pintype "passive")
		)
		(pad "24" smd rect
			(at 0.752 2.742 270)
			(size 0.3 1.1)
			(layers "B.Cu" "B.Mask" "B.Paste")
			(net 305 "Net-(R706-R1.1)")
			(pintype "passive")
		)
		(pad "25" smd rect
			(at 1.252 -2.755 270)
			(size 0.3 1.1)
			(layers "B.Cu" "B.Mask" "B.Paste")
			(net 3 "GND")
			(pintype "passive")
		)
		(pad "26" smd rect
			(at 1.252 2.742 270)
			(size 0.3 1.1)
			(layers "B.Cu" "B.Mask" "B.Paste")
			(net 306 "Net-(R706-R2.1)")
			(pintype "passive")
		)
		(pad "27" smd rect
			(at 1.752 -2.755 270)
			(size 0.3 1.1)
			(layers "B.Cu" "B.Mask" "B.Paste")
			(net 76 "/Compute module/DSI.CLK_N")
			(pintype "passive")
		)
		(pad "28" smd rect
			(at 1.752 2.742 270)
			(size 0.3 1.1)
			(layers "B.Cu" "B.Mask" "B.Paste")
			(net 307 "Net-(R706-R3.1)")
			(pintype "passive")
		)
		(pad "29" smd rect
			(at 2.251 -2.755 270)
			(size 0.3 1.1)
			(layers "B.Cu" "B.Mask" "B.Paste")
			(net 86 "/Compute module/DSI.CLK_P")
			(pintype "passive")
		)
		(pad "30" smd rect
			(at 2.251 2.742 270)
			(size 0.3 1.1)
			(layers "B.Cu" "B.Mask" "B.Paste")
			(net 308 "Net-(R706-R4.1)")
			(pintype "passive")
		)
		(pad "31" smd rect
			(at 2.751 -2.755 270)
			(size 0.3 1.1)
			(layers "B.Cu" "B.Mask" "B.Paste")
			(net 3 "GND")
			(pintype "passive")
		)
		(pad "32" smd rect
			(at 2.751 2.742 270)
			(size 0.3 1.1)
			(layers "B.Cu" "B.Mask" "B.Paste")
			(net 3 "GND")
			(pintype "passive")
		)
		(pad "33" smd rect
			(at 3.251 -2.755 270)
			(size 0.3 1.1)
			(layers "B.Cu" "B.Mask" "B.Paste")
			(net 309 "unconnected-(J701-Pad33)")
			(pintype "passive+no_connect")
		)
		(pad "34" smd rect
			(at 3.251 2.742 270)
			(size 0.3 1.1)
			(layers "B.Cu" "B.Mask" "B.Paste")
			(net 310 "unconnected-(J701-Pad34)")
			(pintype "passive+no_connect")
		)
		(pad "35" smd rect
			(at 3.751 -2.755 270)
			(size 0.3 1.1)
			(layers "B.Cu" "B.Mask" "B.Paste")
			(net 311 "unconnected-(J701-Pad35)")
			(pintype "passive+no_connect")
		)
		(pad "36" smd rect
			(at 3.751 2.742 270)
			(size 0.3 1.1)
			(layers "B.Cu" "B.Mask" "B.Paste")
			(net 312 "unconnected-(J701-Pad36)")
			(pintype "passive+no_connect")
		)
		(pad "37" smd rect
			(at 4.252 -2.755 270)
			(size 0.3 1.1)
			(layers "B.Cu" "B.Mask" "B.Paste")
			(net 313 "unconnected-(J701-Pad37)")
			(pintype "passive+no_connect")
		)
		(pad "38" smd rect
			(at 4.252 2.742 270)
			(size 0.3 1.1)
			(layers "B.Cu" "B.Mask" "B.Paste")
			(net 314 "unconnected-(J701-Pad38)")
			(pintype "passive+no_connect")
		)
		(pad "39" smd rect
			(at 4.752 -2.755 270)
			(size 0.3 1.1)
			(layers "B.Cu" "B.Mask" "B.Paste")
			(net 315 "unconnected-(J701-Pad39)")
			(pintype "passive+no_connect")
		)
		(pad "40" smd rect
			(at 4.752 2.742 270)
			(size 0.3 1.1)
			(layers "B.Cu" "B.Mask" "B.Paste")
			(net 316 "unconnected-(J701-Pad40)")
			(pintype "passive+no_connect")
		)
		(pad "MP" smd rect
			(at -5.949 -2.568 270)
			(size 1.3 1.32)
			(layers "B.Cu" "B.Mask" "B.Paste")
			(net 3 "GND")
			(pintype "passive")
		)
		(pad "MP" smd rect
			(at -5.949 2.552 270)
			(size 1.3 1.32)
			(layers "B.Cu" "B.Mask" "B.Paste")
			(net 3 "GND")
			(pintype "passive")
		)
		(pad "MP" smd rect
			(at 5.953 2.552 270)
			(size 1.3 1.32)
			(layers "B.Cu" "B.Mask" "B.Paste")
			(net 3 "GND")
			(pintype "passive")
		)
		(pad "MP" smd rect
			(at 5.958 -2.568 270)
			(size 1.3 1.32)
			(layers "B.Cu" "B.Mask" "B.Paste")
			(net 3 "GND")
			(pintype "passive")
		)
	)
	(footprint "antmicro-footprints:Nexperia_DFN-10_2.5x1mm_P0.5mm"
		(layer "B.Cu")
		(at 89.505962 172.1785 90)
		(property "Reference" "D702"
			(at -1.198 -1.908 90)
			(layer "B.SilkS")
			(effects
				(font
					(size 0.7 0.7)
					(thickness 0.15)
				)
				(justify right bottom mirror)
			)
		)
		(property "Value" "PUSB3F96X_PASS"
			(at -0.016 -1.705 90)
			(layer "B.Fab")
			(effects
				(font
					(size 0.7 0.7)
					(thickness 0.15)
				)
				(justify right bottom mirror)
			)
		)
		(property "Datasheet" "https://mouser.com/datasheet/2/916/PUSB3F96-1600324.pdf"
			(at 0 0 90)
			(layer "B.Fab")
			(hide yes)
			(effects
				(font
					(size 1.27 1.27)
					(thickness 0.15)
				)
			)
		)
		(property "Manufacturer" "Nexperia"
			(at 0 0 90)
			(unlocked yes)
			(layer "B.Fab")
			(hide yes)
			(effects
				(font
					(size 1 1)
					(thickness 0.15)
				)
				(justify mirror)
			)
		)
		(property "MPN" "PUSB3F96X"
			(at 0 0 90)
			(unlocked yes)
			(layer "B.Fab")
			(hide yes)
			(effects
				(font
					(size 1 1)
					(thickness 0.15)
				)
				(justify mirror)
			)
		)
		(property "Author" "Antmicro"
			(at 0 0 90)
			(unlocked yes)
			(layer "B.Fab")
			(hide yes)
			(effects
				(font
					(size 1 1)
					(thickness 0.15)
				)
				(justify mirror)
			)
		)
		(property "License" "Apache-2.0"
			(at 0 0 90)
			(unlocked yes)
			(layer "B.Fab")
			(hide yes)
			(effects
				(font
					(size 1 1)
					(thickness 0.15)
				)
				(justify mirror)
			)
		)
		(sheetname "/Display/")
		(sheetfile "display.kicad_sch")
		(attr smd)
		(fp_line
			(start 1.375 -0.4)
			(end 1.375 0.4)
			(stroke
				(width 0.15)
				(type solid)
			)
			(layer "B.SilkS")
		)
		(fp_line
			(start -1.375 0.4)
			(end -1.375 -0.4)
			(stroke
				(width 0.15)
				(type solid)
			)
			(layer "B.SilkS")
		)
		(fp_circle
			(center -1.4 -0.7)
			(end -1.349 -0.7)
			(stroke
				(width 0.15)
				(type solid)
			)
			(fill yes)
			(layer "B.SilkS")
		)
		(fp_rect
			(start -1.4 0.725)
			(end 1.4 -0.725)
			(stroke
				(width 0.05)
				(type solid)
			)
			(fill no)
			(layer "B.CrtYd")
		)
		(fp_line
			(start 1.25 -0.5)
			(end 1.25 0.5)
			(stroke
				(width 0.15)
				(type solid)
			)
			(layer "B.Fab")
		)
		(fp_line
			(start -0.9 -0.5)
			(end 1.25 -0.5)
			(stroke
				(width 0.15)
				(type solid)
			)
			(layer "B.Fab")
		)
		(fp_line
			(start -1.25 -0.15)
			(end -0.9 -0.5)
			(stroke
				(width 0.15)
				(type solid)
			)
			(layer "B.Fab")
		)
		(fp_line
			(start 1.25 0.5)
			(end -1.25 0.5)
			(stroke
				(width 0.15)
				(type solid)
			)
			(layer "B.Fab")
		)
		(fp_line
			(start -1.25 0.5)
			(end -1.25 -0.15)
			(stroke
				(width 0.15)
				(type solid)
			)
			(layer "B.Fab")
		)
		(fp_text user "Author: Antmicro"
			(at -1.367 -4.905 270)
			(layer "B.Fab")
			(effects
				(font
					(size 0.7 0.7)
					(thickness 0.15)
				)
				(justify left bottom mirror)
			)
		)
		(fp_text user "${REFERENCE}"
			(at -1.367 -3.704 270)
			(layer "B.Fab")
			(effects
				(font
					(size 0.7 0.7)
					(thickness 0.15)
				)
				(justify left bottom mirror)
			)
		)
		(fp_text user "License: Apache-2.0"
			(at -1.367 -6.105 270)
			(layer "B.Fab")
			(effects
				(font
					(size 0.7 0.7)
					(thickness 0.15)
				)
				(justify left bottom mirror)
			)
		)
		(pad "1" smd rect
			(at -1 -0.3875 90)
			(size 0.2 0.475)
			(layers "B.Cu" "B.Mask" "B.Paste")
			(net 74 "/Compute module/DSI.D1_N")
			(pinfunction "CH1")
			(pintype "passive")
			(solder_mask_margin 0.05)
		)
		(pad "2" smd rect
			(at -0.5 -0.3875 90)
			(size 0.2 0.475)
			(layers "B.Cu" "B.Mask" "B.Paste")
			(net 75 "/Compute module/DSI.D1_P")
			(pinfunction "CH2")
			(pintype "passive")
			(solder_mask_margin 0.05)
		)
		(pad "3" smd rect
			(at 0 -0.3875 90)
			(size 0.2 0.475)
			(layers "B.Cu" "B.Mask" "B.Paste")
			(net 3 "GND")
			(pinfunction "GND")
			(pintype "passive")
			(solder_mask_margin 0.05)
		)
		(pad "4" smd rect
			(at 0.5 -0.3875 90)
			(size 0.2 0.475)
			(layers "B.Cu" "B.Mask" "B.Paste")
			(net 72 "/Compute module/DSI.D0_N")
			(pinfunction "CH3")
			(pintype "passive")
			(solder_mask_margin 0.05)
		)
		(pad "5" smd rect
			(at 1 -0.3875 90)
			(size 0.2 0.475)
			(layers "B.Cu" "B.Mask" "B.Paste")
			(net 73 "/Compute module/DSI.D0_P")
			(pinfunction "CH4")
			(pintype "passive")
			(solder_mask_margin 0.05)
		)
		(pad "6" smd rect
			(at 1 0.3875 90)
			(size 0.2 0.475)
			(layers "B.Cu" "B.Mask" "B.Paste")
			(net 73 "/Compute module/DSI.D0_P")
			(pinfunction "CH4")
			(pintype "passive")
			(solder_mask_margin 0.05)
		)
		(pad "7" smd rect
			(at 0.5 0.3875 90)
			(size 0.2 0.475)
			(layers "B.Cu" "B.Mask" "B.Paste")
			(net 72 "/Compute module/DSI.D0_N")
			(pinfunction "CH3")
			(pintype "passive")
			(solder_mask_margin 0.05)
		)
		(pad "8" smd rect
			(at 0 0.3875 90)
			(size 0.2 0.475)
			(layers "B.Cu" "B.Mask" "B.Paste")
			(net 3 "GND")
			(pinfunction "GND")
			(pintype "passive")
			(solder_mask_margin 0.05)
		)
		(pad "9" smd rect
			(at -0.501 0.3875 90)
			(size 0.2 0.475)
			(layers "B.Cu" "B.Mask" "B.Paste")
			(net 75 "/Compute module/DSI.D1_P")
			(pinfunction "CH2")
			(pintype "passive")
			(solder_mask_margin 0.05)
		)
		(pad "10" smd rect
			(at -1 0.3875 90)
			(size 0.2 0.475)
			(layers "B.Cu" "B.Mask" "B.Paste")
			(net 74 "/Compute module/DSI.D1_N")
			(pinfunction "CH1")
			(pintype "passive")
			(solder_mask_margin 0.05)
		)
	)
	(footprint "antmicro-footprints:R_0402_1005Metric"
		(layer "B.Cu")
		(at 78.767962 151.2415 180)
		(descr "Resistor SMD 0402")
		(tags "resistor SMD 0402")
		(property "Reference" "R241"
			(at -4.88 0.245 0)
			(layer "B.SilkS")
			(effects
				(font
					(size 0.7 0.7)
					(thickness 0.15)
				)
				(justify left bottom mirror)
			)
		)
		(property "Value" "R_2k2_0402"
			(at -1.011843 -1.772047 0)
			(layer "B.Fab")
			(effects
				(font
					(size 0.7 0.7)
					(thickness 0.15)
				)
				(justify left bottom mirror)
			)
		)
		(property "Datasheet" "https://www.bourns.com/docs/product-datasheets/cr.pdf"
			(at 0 0 180)
			(layer "B.Fab")
			(hide yes)
			(effects
				(font
					(size 1.27 1.27)
					(thickness 0.15)
				)
			)
		)
		(property "MPN" "CR0402-FX-2201GLF"
			(at 0 0 180)
			(unlocked yes)
			(layer "B.Fab")
			(hide yes)
			(effects
				(font
					(size 1 1)
					(thickness 0.15)
				)
				(justify mirror)
			)
		)
		(property "Manufacturer" "Bourns"
			(at 0 0 180)
			(unlocked yes)
			(layer "B.Fab")
			(hide yes)
			(effects
				(font
					(size 1 1)
					(thickness 0.15)
				)
				(justify mirror)
			)
		)
		(property "License" "Apache-2.0"
			(at 0 0 180)
			(unlocked yes)
			(layer "B.Fab")
			(hide yes)
			(effects
				(font
					(size 1 1)
					(thickness 0.15)
				)
				(justify mirror)
			)
		)
		(property "Author" "Antmicro"
			(at 0 0 180)
			(unlocked yes)
			(layer "B.Fab")
			(hide yes)
			(effects
				(font
					(size 1 1)
					(thickness 0.15)
				)
				(justify mirror)
			)
		)
		(property "Val" "2k2"
			(at 0 0 180)
			(unlocked yes)
			(layer "B.Fab")
			(hide yes)
			(effects
				(font
					(size 1 1)
					(thickness 0.15)
				)
				(justify mirror)
			)
		)
		(property "Tolerance" "1%"
			(at 0 0 180)
			(unlocked yes)
			(layer "B.Fab")
			(hide yes)
			(effects
				(font
					(size 1 1)
					(thickness 0.15)
				)
				(justify mirror)
			)
		)
		(sheetname "/Compute module/")
		(sheetfile "compute-module.kicad_sch")
		(attr smd)
		(fp_rect
			(start -0.925 0.47)
			(end 0.925 -0.47)
			(stroke
				(width 0.05)
				(type default)
			)
			(fill no)
			(layer "B.CrtYd")
		)
		(fp_rect
			(start -0.5 0.25)
			(end 0.5 -0.25)
			(stroke
				(width 0.15)
				(type solid)
			)
			(fill no)
			(layer "B.Fab")
		)
		(fp_text user "License: Apache-2.0"
			(at -0.95 -5.169 0)
			(layer "B.Fab")
			(effects
				(font
					(size 0.7 0.7)
					(thickness 0.15)
				)
				(justify left bottom mirror)
			)
		)
		(fp_text user "${REFERENCE}"
			(at -0.95 -3.168 0)
			(layer "B.Fab")
			(effects
				(font
					(size 0.7 0.7)
					(thickness 0.15)
				)
				(justify left bottom mirror)
			)
		)
		(fp_text user "Author: Antmicro"
			(at -0.95 -4.169 0)
			(layer "B.Fab")
			(effects
				(font
					(size 0.7 0.7)
					(thickness 0.15)
				)
				(justify left bottom mirror)
			)
		)
		(pad "1" smd roundrect
			(at -0.48 0 180)
			(size 0.59 0.64)
			(layers "B.Cu" "B.Mask" "B.Paste")
			(roundrect_rratio 0.25)
			(net 446 "/Compute module/GPIO.1{slash}SCL0")
			(pintype "passive")
		)
		(pad "2" smd roundrect
			(at 0.48 0 180)
			(size 0.59 0.64)
			(layers "B.Cu" "B.Mask" "B.Paste")
			(roundrect_rratio 0.25)
			(net 18 "V_{IO}")
			(pintype "passive")
		)
	)
)
